# T6G (Grand Teton) — schematic netlist excerpt (pin names and nets, part order shuffled) for the footprints in the layout excerpt that follows; sources: Cadence DE-HDL packaged netlist, KiCad conversion of 04192023_DAF0TMB3IC0_F0TG_MB_C_brd_V02_OCP.brd

C2574  Q_CAP  22UF 4V 20% X6S  pkg C0402  page 70 : A = PVDDCR_SOC_P0 ; B = GND
C2330  Q_CAP  22UF 4V 20% X6S  pkg C0402  page 73 : A = PVDDCR_CPU0_P1 ; B = GND

(kicad_pcb
	(version 20260206)
	(generator "pcbnew")
	(generator_version "10.0")
	(general
		(thickness 1.6)
		(legacy_teardrops no)
	)
	(paper "A4")
	(title_block
		(title "04192023_DAF0TMB3IC0_F0TG_MB_C_brd_V02_OCP.brd")
		(comment 1 "Grand Teton / footprints 6968-6969 of 8354")
	)
	(layers
		(0 "F.Cu" signal "TOP")
		(4 "In1.Cu" signal "GND")
		(6 "In2.Cu" signal "IN1")
		(8 "In3.Cu" signal "GND1")
		(10 "In4.Cu" signal "IN2")
		(12 "In5.Cu" signal "GND2")
		(14 "In6.Cu" signal "IN3")
		(16 "In7.Cu" signal "GND3")
		(18 "In8.Cu" signal "VCC")
		(20 "In9.Cu" signal "VCC1")
		(22 "In10.Cu" signal "GND4")
		(24 "In11.Cu" signal "IN4")
		(26 "In12.Cu" signal "GND5")
		(28 "In13.Cu" signal "IN5")
		(30 "In14.Cu" signal "GND6")
		(32 "In15.Cu" signal "IN6")
		(34 "In16.Cu" signal "GND7")
		(2 "B.Cu" signal "BOTTOM")
		(9 "F.Adhes" user "F.Adhesive")
		(11 "B.Adhes" user "B.Adhesive")
		(13 "F.Paste" user "Package Geometry/Pastemask Top")
		(15 "B.Paste" user "Package Geometry/Pastemask Bottom")
		(5 "F.SilkS" user "Ref Des/Silkscreen Top")
		(7 "B.SilkS" user "Ref Des/Silkscreen Bottom")
		(1 "F.Mask" user "Board Geometry/Soldermask Top")
		(3 "B.Mask" user "Board Geometry/Soldermask Bottom")
		(17 "Dwgs.User" user "User.Drawings")
		(19 "Cmts.User" user "User.Comments")
		(21 "Eco1.User" user "User.Eco1")
		(23 "Eco2.User" user "User.Eco2")
		(25 "Edge.Cuts" user "Board Geometry/Outline")
		(27 "Margin" user)
		(31 "F.CrtYd" user "Package Geometry/Place Bound Top")
		(29 "B.CrtYd" user "Package Geometry/Place Bound Bottom")
		(35 "F.Fab" user "Ref Des/Assembly Top")
		(33 "B.Fab" user "Ref Des/Assembly Bottom")
	)
	(footprint ""
		(layer "B.Cu")
		(at 118.432834 -245.487952 180)
		(property "Reference" "C2330"
			(at 0 0 0)
			(layer "B.SilkS")
			(hide yes)
			(effects
				(font
					(size 1.27 1.27)
				)
				(justify mirror)
			)
		)
		(property "Value" ""
			(at 0 0 0)
			(layer "B.Fab")
			(effects
				(font
					(size 1.27 1.27)
				)
				(justify mirror)
			)
		)
		(duplicate_pad_numbers_are_jumpers no)
		(fp_line
			(start 0.7874 0.4064)
			(end 0.7874 -0.4064)
			(stroke
				(width 0.1524)
				(type default)
			)
			(layer "B.SilkS")
		)
		(fp_line
			(start 0.7874 -0.4064)
			(end -0.7874 -0.4064)
			(stroke
				(width 0.1524)
				(type default)
			)
			(layer "B.SilkS")
		)
		(fp_line
			(start -0.7874 0.4064)
			(end 0.7874 0.4064)
			(stroke
				(width 0.1524)
				(type default)
			)
			(layer "B.SilkS")
		)
		(fp_line
			(start -0.7874 -0.4064)
			(end -0.7874 0.4064)
			(stroke
				(width 0.1524)
				(type default)
			)
			(layer "B.SilkS")
		)
		(fp_line
			(start 0.67945 0.3048)
			(end 0.67945 -0.305054)
			(stroke
				(width 0.1)
				(type default)
			)
			(layer "B.Fab")
		)
		(fp_line
			(start 0.67945 -0.305054)
			(end 0.12065 -0.305054)
			(stroke
				(width 0.1)
				(type default)
			)
			(layer "B.Fab")
		)
		(fp_line
			(start 0.12065 0.3048)
			(end 0.67945 0.3048)
			(stroke
				(width 0.1)
				(type default)
			)
			(layer "B.Fab")
		)
		(fp_line
			(start 0.12065 0.2794)
			(end 0.12065 0.3048)
			(stroke
				(width 0.1)
				(type default)
			)
			(layer "B.Fab")
		)
		(fp_line
			(start 0.12065 -0.2794)
			(end -0.12065 -0.2794)
			(stroke
				(width 0.1)
				(type default)
			)
			(layer "B.Fab")
		)
		(fp_line
			(start 0.12065 -0.305054)
			(end 0.12065 -0.2794)
			(stroke
				(width 0.1)
				(type default)
			)
			(layer "B.Fab")
		)
		(fp_line
			(start -0.120396 0.3048)
			(end -0.120396 0.2794)
			(stroke
				(width 0.1)
				(type default)
			)
			(layer "B.Fab")
		)
		(fp_line
			(start -0.120396 0.2794)
			(end 0.12065 0.2794)
			(stroke
				(width 0.1)
				(type default)
			)
			(layer "B.Fab")
		)
		(fp_line
			(start -0.12065 -0.2794)
			(end -0.12065 -0.3048)
			(stroke
				(width 0.1)
				(type default)
			)
			(layer "B.Fab")
		)
		(fp_line
			(start -0.12065 -0.3048)
			(end -0.67945 -0.3048)
			(stroke
				(width 0.1)
				(type default)
			)
			(layer "B.Fab")
		)
		(fp_line
			(start -0.67945 0.3048)
			(end -0.120396 0.3048)
			(stroke
				(width 0.1)
				(type default)
			)
			(layer "B.Fab")
		)
		(fp_line
			(start -0.67945 -0.3048)
			(end -0.67945 0.3048)
			(stroke
				(width 0.1)
				(type default)
			)
			(layer "B.Fab")
		)
		(pad "1" smd circle
			(at 0.40005 0)
			(size 0 0)
			(layers "B.Cu" "B.Mask" "B.Paste")
			(net "PVDDCR_CPU0_P1")
		)
		(pad "2" smd circle
			(at -0.40005 0)
			(size 0 0)
			(layers "B.Cu" "B.Mask" "B.Paste")
			(net "GND")
		)
	)
	(footprint ""
		(layer "B.Cu")
		(at 349.834454 -262.70331)
		(property "Reference" "C2574"
			(at 0 0 0)
			(layer "B.SilkS")
			(hide yes)
			(effects
				(font
					(size 1.27 1.27)
				)
				(justify mirror)
			)
		)
		(property "Value" ""
			(at 0 0 0)
			(layer "B.Fab")
			(effects
				(font
					(size 1.27 1.27)
				)
				(justify mirror)
			)
		)
		(duplicate_pad_numbers_are_jumpers no)
		(fp_line
			(start -0.7874 -0.4064)
			(end -0.7874 0.4064)
			(stroke
				(width 0.1524)
				(type default)
			)
			(layer "B.SilkS")
		)
		(fp_line
			(start -0.7874 0.4064)
			(end 0.7874 0.4064)
			(stroke
				(width 0.1524)
				(type default)
			)
			(layer "B.SilkS")
		)
		(fp_line
			(start 0.7874 -0.4064)
			(end -0.7874 -0.4064)
			(stroke
				(width 0.1524)
				(type default)
			)
			(layer "B.SilkS")
		)
		(fp_line
			(start 0.7874 0.4064)
			(end 0.7874 -0.4064)
			(stroke
				(width 0.1524)
				(type default)
			)
			(layer "B.SilkS")
		)
		(fp_line
			(start -0.67945 -0.3048)
			(end -0.67945 0.3048)
			(stroke
				(width 0.1)
				(type default)
			)
			(layer "B.Fab")
		)
		(fp_line
			(start -0.67945 0.3048)
			(end -0.120396 0.3048)
			(stroke
				(width 0.1)
				(type default)
			)
			(layer "B.Fab")
		)
		(fp_line
			(start -0.12065 -0.3048)
			(end -0.67945 -0.3048)
			(stroke
				(width 0.1)
				(type default)
			)
			(layer "B.Fab")
		)
		(fp_line
			(start -0.12065 -0.2794)
			(end -0.12065 -0.3048)
			(stroke
				(width 0.1)
				(type default)
			)
			(layer "B.Fab")
		)
		(fp_line
			(start -0.120396 0.2794)
			(end 0.12065 0.2794)
			(stroke
				(width 0.1)
				(type default)
			)
			(layer "B.Fab")
		)
		(fp_line
			(start -0.120396 0.3048)
			(end -0.120396 0.2794)
			(stroke
				(width 0.1)
				(type default)
			)
			(layer "B.Fab")
		)
		(fp_line
			(start 0.12065 -0.305054)
			(end 0.12065 -0.2794)
			(stroke
				(width 0.1)
				(type default)
			)
			(layer "B.Fab")
		)
		(fp_line
			(start 0.12065 -0.2794)
			(end -0.12065 -0.2794)
			(stroke
				(width 0.1)
				(type default)
			)
			(layer "B.Fab")
		)
		(fp_line
			(start 0.12065 0.2794)
			(end 0.12065 0.3048)
			(stroke
				(width 0.1)
				(type default)
			)
			(layer "B.Fab")
		)
		(fp_line
			(start 0.12065 0.3048)
			(end 0.67945 0.3048)
			(stroke
				(width 0.1)
				(type default)
			)
			(layer "B.Fab")
		)
		(fp_line
			(start 0.67945 -0.305054)
			(end 0.12065 -0.305054)
			(stroke
				(width 0.1)
				(type default)
			)
			(layer "B.Fab")
		)
		(fp_line
			(start 0.67945 0.3048)
			(end 0.67945 -0.305054)
			(stroke
				(width 0.1)
				(type default)
			)
			(layer "B.Fab")
		)
		(pad "1" smd circle
			(at 0.40005 0 180)
			(size 0 0)
			(layers "B.Cu" "B.Mask" "B.Paste")
			(net "PVDDCR_SOC_P0")
		)
		(pad "2" smd circle
			(at -0.40005 0 180)
			(size 0 0)
			(layers "B.Cu" "B.Mask" "B.Paste")
			(net "GND")
		)
	)
)
